(kicad_pcb
	(version 20260206)
	(generator "pcbnew")
	(generator_version "10.0")
	(general
		(thickness 1.6)
		(legacy_teardrops no)
	)
	(paper "A4")
	(title_block
		(title "Bryce Canyon_IOM_IOC_16318-2_OCP.brd")
		(comment 1 "Bryce Canyon / footprints 345-351 of 1605")
	)
	(layers
		(0 "F.Cu" signal "TOP")
		(4 "In1.Cu" signal "L2GND")
		(6 "In2.Cu" signal "L3")
		(8 "In3.Cu" signal "L4VCC")
		(10 "In4.Cu" signal "L5VCC")
		(12 "In5.Cu" signal "L6")
		(14 "In6.Cu" signal "L7GND")
		(2 "B.Cu" signal "BOTTOM")
		(9 "F.Adhes" user "F.Adhesive")
		(11 "B.Adhes" user "B.Adhesive")
		(13 "F.Paste" user "Package Geometry/Pastemask Top")
		(15 "B.Paste" user "Package Geometry/Pastemask Bottom")
		(5 "F.SilkS" user "Ref Des/Silkscreen Top")
		(7 "B.SilkS" user "Ref Des/Silkscreen Bottom")
		(1 "F.Mask" user "Board Geometry/Soldermask Top")
		(3 "B.Mask" user "Board Geometry/Soldermask Bottom")
		(17 "Dwgs.User" user "User.Drawings")
		(19 "Cmts.User" user "User.Comments")
		(21 "Eco1.User" user "User.Eco1")
		(23 "Eco2.User" user "User.Eco2")
		(25 "Edge.Cuts" user "Board Geometry/Outline")
		(27 "Margin" user)
		(31 "F.CrtYd" user "Package Geometry/Place Bound Top")
		(29 "B.CrtYd" user "Package Geometry/Place Bound Bottom")
		(35 "F.Fab" user "Ref Des/Assembly Top")
		(33 "B.Fab" user "Ref Des/Assembly Bottom")
	)
	(footprint ""
		(layer "F.Cu")
		(at 179.2351 -48.1457)
		(property "Reference" "R671"
			(at 0 0 0)
			(layer "F.SilkS")
			(hide yes)
			(effects
				(font
					(size 1.27 1.27)
				)
			)
		)
		(property "Value" "10KR2F-2-GP"
			(at 0.064008 -3.993896 0)
			(unlocked yes)
			(layer "F.Fab")
			(hide yes)
			(effects
				(font
					(size 1.016 1.016)
					(thickness 0.1524)
				)
			)
		)
		(property "Device Type" "R402H16"
			(at 0.064008 -5.517896 0)
			(unlocked yes)
			(layer "F.Fab")
			(hide yes)
			(effects
				(font
					(size 1.016 1.016)
					(thickness 0.1524)
				)
			)
		)
		(duplicate_pad_numbers_are_jumpers no)
		(fp_line
			(start -0.508 -0.9398)
			(end -0.508 0.9398)
			(stroke
				(width 0.1524)
				(type default)
			)
			(layer "F.SilkS")
		)
		(fp_line
			(start 0.508 -0.9398)
			(end -0.508 -0.9398)
			(stroke
				(width 0.1524)
				(type default)
			)
			(layer "F.SilkS")
		)
		(fp_rect
			(start -0.508 0.9398)
			(end 0.508 -0.9398)
			(stroke
				(width 0)
				(type default)
			)
			(fill no)
			(layer "F.CrtYd")
		)
		(fp_rect
			(start -0.508 0.9398)
			(end 0.508 -0.9398)
			(stroke
				(width 0)
				(type default)
			)
			(fill no)
			(layer "F.Fab")
		)
		(pad "1" smd custom
			(at 0 -0.4445)
			(size 0.1397 0.1397)
			(layers "F.Cu" "F.Mask" "F.Paste")
			(net "XM_ADDR_5")
			(options
				(clearance outline)
				(anchor circle)
			)
			(primitives
				(gr_poly
					(pts
						(arc
							(start -0.1778 -0.2794)
							(mid -0.249642 -0.249642)
							(end -0.2794 -0.1778)
						)
						(arc
							(start -0.2794 0.1778)
							(mid -0.249642 0.249642)
							(end -0.1778 0.2794)
						)
						(arc
							(start 0.1778 0.2794)
							(mid 0.249642 0.249642)
							(end 0.2794 0.1778)
						)
						(arc
							(start 0.2794 -0.1778)
							(mid 0.249642 -0.249642)
							(end 0.1778 -0.2794)
						)
					)
					(width 0)
					(fill yes)
				)
			)
		)
		(pad "2" smd custom
			(at 0 0.4445)
			(size 0.1397 0.1397)
			(layers "F.Cu" "F.Mask" "F.Paste")
			(net "GND")
			(options
				(clearance outline)
				(anchor circle)
			)
			(primitives
				(gr_poly
					(pts
						(arc
							(start -0.1778 -0.2794)
							(mid -0.249642 -0.249642)
							(end -0.2794 -0.1778)
						)
						(arc
							(start -0.2794 0.1778)
							(mid -0.249642 0.249642)
							(end -0.1778 0.2794)
						)
						(arc
							(start 0.1778 0.2794)
							(mid 0.249642 0.249642)
							(end 0.2794 0.1778)
						)
						(arc
							(start 0.2794 -0.1778)
							(mid 0.249642 -0.249642)
							(end 0.1778 -0.2794)
						)
					)
					(width 0)
					(fill yes)
				)
			)
		)
	)
	(footprint ""
		(layer "F.Cu")
		(at 68.1482 -163.322 -90)
		(property "Reference" "R73"
			(at 0 0 270)
			(layer "F.SilkS")
			(hide yes)
			(effects
				(font
					(size 1.27 1.27)
				)
			)
		)
		(property "Value" "4K75R2F-1-GP"
			(at 0.064008 -3.993896 270)
			(unlocked yes)
			(layer "F.Fab")
			(hide yes)
			(effects
				(font
					(size 1.016 1.016)
					(thickness 0.1524)
				)
			)
		)
		(property "Device Type" "R402H16"
			(at 0.064008 -5.517896 270)
			(unlocked yes)
			(layer "F.Fab")
			(hide yes)
			(effects
				(font
					(size 1.016 1.016)
					(thickness 0.1524)
				)
			)
		)
		(duplicate_pad_numbers_are_jumpers no)
		(fp_line
			(start -0.508 -0.9398)
			(end -0.508 0.9398)
			(stroke
				(width 0.1524)
				(type default)
			)
			(layer "F.SilkS")
		)
		(fp_line
			(start 0.508 -0.9398)
			(end -0.508 -0.9398)
			(stroke
				(width 0.1524)
				(type default)
			)
			(layer "F.SilkS")
		)
		(fp_rect
			(start -0.508 0.9398)
			(end 0.508 -0.9398)
			(stroke
				(width 0)
				(type default)
			)
			(fill no)
			(layer "F.CrtYd")
		)
		(fp_rect
			(start -0.508 0.9398)
			(end 0.508 -0.9398)
			(stroke
				(width 0)
				(type default)
			)
			(fill no)
			(layer "F.Fab")
		)
		(pad "1" smd custom
			(at 0 -0.4445 270)
			(size 0.1397 0.1397)
			(layers "F.Cu" "F.Mask" "F.Paste")
			(net "P3V3_STBY")
			(options
				(clearance outline)
				(anchor circle)
			)
			(primitives
				(gr_poly
					(pts
						(arc
							(start -0.1778 -0.2794)
							(mid -0.249642 -0.249642)
							(end -0.2794 -0.1778)
						)
						(arc
							(start -0.2794 0.1778)
							(mid -0.249642 0.249642)
							(end -0.1778 0.2794)
						)
						(arc
							(start 0.1778 0.2794)
							(mid 0.249642 0.249642)
							(end 0.2794 0.1778)
						)
						(arc
							(start 0.2794 -0.1778)
							(mid 0.249642 -0.249642)
							(end 0.1778 -0.2794)
						)
					)
					(width 0)
					(fill yes)
				)
			)
		)
		(pad "2" smd custom
			(at 0 0.4445 270)
			(size 0.1397 0.1397)
			(layers "F.Cu" "F.Mask" "F.Paste")
			(net "BMC_TPM_RST_N")
			(options
				(clearance outline)
				(anchor circle)
			)
			(primitives
				(gr_poly
					(pts
						(arc
							(start -0.1778 -0.2794)
							(mid -0.249642 -0.249642)
							(end -0.2794 -0.1778)
						)
						(arc
							(start -0.2794 0.1778)
							(mid -0.249642 0.249642)
							(end -0.1778 0.2794)
						)
						(arc
							(start 0.1778 0.2794)
							(mid 0.249642 0.249642)
							(end 0.2794 0.1778)
						)
						(arc
							(start 0.2794 -0.1778)
							(mid 0.249642 -0.249642)
							(end 0.1778 -0.2794)
						)
					)
					(width 0)
					(fill yes)
				)
			)
		)
	)
	(footprint ""
		(layer "F.Cu")
		(at 67.5386 -140.2334 90)
		(property "Reference" "R56"
			(at 0 0 90)
			(layer "F.SilkS")
			(hide yes)
			(effects
				(font
					(size 1.27 1.27)
				)
			)
		)
		(property "Value" "10KR2F-2-GP"
			(at 0.064008 -3.993896 90)
			(unlocked yes)
			(layer "F.Fab")
			(hide yes)
			(effects
				(font
					(size 1.016 1.016)
					(thickness 0.1524)
				)
			)
		)
		(property "Device Type" "R402H16"
			(at 0.064008 -5.517896 90)
			(unlocked yes)
			(layer "F.Fab")
			(hide yes)
			(effects
				(font
					(size 1.016 1.016)
					(thickness 0.1524)
				)
			)
		)
		(duplicate_pad_numbers_are_jumpers no)
		(fp_line
			(start 0.508 -0.9398)
			(end -0.508 -0.9398)
			(stroke
				(width 0.1524)
				(type default)
			)
			(layer "F.SilkS")
		)
		(fp_line
			(start -0.508 -0.9398)
			(end -0.508 0.9398)
			(stroke
				(width 0.1524)
				(type default)
			)
			(layer "F.SilkS")
		)
		(fp_rect
			(start -0.508 0.9398)
			(end 0.508 -0.9398)
			(stroke
				(width 0)
				(type default)
			)
			(fill no)
			(layer "F.CrtYd")
		)
		(fp_rect
			(start -0.508 0.9398)
			(end 0.508 -0.9398)
			(stroke
				(width 0)
				(type default)
			)
			(fill no)
			(layer "F.Fab")
		)
		(pad "1" smd custom
			(at 0 -0.4445 90)
			(size 0.1397 0.1397)
			(layers "F.Cu" "F.Mask" "F.Paste")
			(net "P3V3_STBY")
			(options
				(clearance outline)
				(anchor circle)
			)
			(primitives
				(gr_poly
					(pts
						(arc
							(start -0.1778 -0.2794)
							(mid -0.249642 -0.249642)
							(end -0.2794 -0.1778)
						)
						(arc
							(start -0.2794 0.1778)
							(mid -0.249642 0.249642)
							(end -0.1778 0.2794)
						)
						(arc
							(start 0.1778 0.2794)
							(mid 0.249642 0.249642)
							(end 0.2794 0.1778)
						)
						(arc
							(start 0.2794 -0.1778)
							(mid 0.249642 -0.249642)
							(end 0.1778 -0.2794)
						)
					)
					(width 0)
					(fill yes)
				)
			)
		)
		(pad "2" smd custom
			(at 0 0.4445 90)
			(size 0.1397 0.1397)
			(layers "F.Cu" "F.Mask" "F.Paste")
			(net "FP_RETBTN")
			(options
				(clearance outline)
				(anchor circle)
			)
			(primitives
				(gr_poly
					(pts
						(arc
							(start -0.1778 -0.2794)
							(mid -0.249642 -0.249642)
							(end -0.2794 -0.1778)
						)
						(arc
							(start -0.2794 0.1778)
							(mid -0.249642 0.249642)
							(end -0.1778 0.2794)
						)
						(arc
							(start 0.1778 0.2794)
							(mid 0.249642 0.249642)
							(end 0.2794 0.1778)
						)
						(arc
							(start 0.2794 -0.1778)
							(mid 0.249642 -0.249642)
							(end 0.1778 -0.2794)
						)
					)
					(width 0)
					(fill yes)
				)
			)
		)
	)
	(footprint ""
		(layer "F.Cu")
		(at 193.5988 -48.387 180)
		(property "Reference" "R645"
			(at 0 0 180)
			(layer "F.SilkS")
			(hide yes)
			(effects
				(font
					(size 1.27 1.27)
				)
			)
		)
		(property "Value" "10KR2F-2-GP"
			(at 0.064008 -3.993896 180)
			(unlocked yes)
			(layer "F.Fab")
			(hide yes)
			(effects
				(font
					(size 1.016 1.016)
					(thickness 0.1524)
				)
			)
		)
		(property "Device Type" "R402H16"
			(at 0.064008 -5.517896 180)
			(unlocked yes)
			(layer "F.Fab")
			(hide yes)
			(effects
				(font
					(size 1.016 1.016)
					(thickness 0.1524)
				)
			)
		)
		(duplicate_pad_numbers_are_jumpers no)
		(fp_line
			(start 0.508 -0.9398)
			(end -0.508 -0.9398)
			(stroke
				(width 0.1524)
				(type default)
			)
			(layer "F.SilkS")
		)
		(fp_line
			(start -0.508 -0.9398)
			(end -0.508 0.9398)
			(stroke
				(width 0.1524)
				(type default)
			)
			(layer "F.SilkS")
		)
		(fp_rect
			(start -0.508 0.9398)
			(end 0.508 -0.9398)
			(stroke
				(width 0)
				(type default)
			)
			(fill no)
			(layer "F.CrtYd")
		)
		(fp_rect
			(start -0.508 0.9398)
			(end 0.508 -0.9398)
			(stroke
				(width 0)
				(type default)
			)
			(fill no)
			(layer "F.Fab")
		)
		(pad "1" smd custom
			(at 0 -0.4445 180)
			(size 0.1397 0.1397)
			(layers "F.Cu" "F.Mask" "F.Paste")
			(net "P1V8")
			(options
				(clearance outline)
				(anchor circle)
			)
			(primitives
				(gr_poly
					(pts
						(arc
							(start -0.1778 -0.2794)
							(mid -0.249642 -0.249642)
							(end -0.2794 -0.1778)
						)
						(arc
							(start -0.2794 0.1778)
							(mid -0.249642 0.249642)
							(end -0.1778 0.2794)
						)
						(arc
							(start 0.1778 0.2794)
							(mid 0.249642 0.249642)
							(end 0.2794 0.1778)
						)
						(arc
							(start 0.2794 -0.1778)
							(mid 0.249642 -0.249642)
							(end 0.1778 -0.2794)
						)
					)
					(width 0)
					(fill yes)
				)
			)
		)
		(pad "2" smd custom
			(at 0 0.4445 180)
			(size 0.1397 0.1397)
			(layers "F.Cu" "F.Mask" "F.Paste")
			(net "LSI_TN")
			(options
				(clearance outline)
				(anchor circle)
			)
			(primitives
				(gr_poly
					(pts
						(arc
							(start -0.1778 -0.2794)
							(mid -0.249642 -0.249642)
							(end -0.2794 -0.1778)
						)
						(arc
							(start -0.2794 0.1778)
							(mid -0.249642 0.249642)
							(end -0.1778 0.2794)
						)
						(arc
							(start 0.1778 0.2794)
							(mid 0.249642 0.249642)
							(end 0.2794 0.1778)
						)
						(arc
							(start 0.2794 -0.1778)
							(mid 0.249642 -0.249642)
							(end 0.1778 -0.2794)
						)
					)
					(width 0)
					(fill yes)
				)
			)
		)
	)
	(footprint ""
		(layer "F.Cu")
		(at 82.457544 -160.376616 180)
		(property "Reference" "C235"
			(at 0 0 180)
			(layer "F.SilkS")
			(hide yes)
			(effects
				(font
					(size 1.27 1.27)
				)
			)
		)
		(property "Value" "SC10U6D3V5KX-4GP"
			(at -0.0762 -6.1214 180)
			(unlocked yes)
			(layer "F.Fab")
			(hide yes)
			(effects
				(font
					(size 1.016 1.016)
					(thickness 0.1524)
				)
			)
		)
		(property "Device Type" "C805H58"
			(at -0.0762 -8.1534 180)
			(unlocked yes)
			(layer "F.Fab")
			(hide yes)
			(effects
				(font
					(size 1.016 1.016)
					(thickness 0.1524)
				)
			)
		)
		(duplicate_pad_numbers_are_jumpers no)
		(fp_line
			(start 0.635 0)
			(end -0.635 0)
			(stroke
				(width 0.508)
				(type default)
			)
			(layer "F.SilkS")
		)
		(fp_rect
			(start -0.9652 1.778)
			(end 0.9652 -1.778)
			(stroke
				(width 0)
				(type default)
			)
			(fill no)
			(layer "F.CrtYd")
		)
		(fp_poly
			(pts
				(xy -0.9652 -1.778) (xy 0.9652 -1.778) (xy 0.9652 1.778) (xy -0.9652 1.778)
			)
			(stroke
				(width 0)
				(type default)
			)
			(fill no)
			(layer "F.Fab")
		)
		(pad "1" smd rect
			(at 0 -0.9652 180)
			(size 1.397 1.143)
			(layers "F.Cu" "F.Mask" "F.Paste")
			(net "TPS74801_P1V15_STBY_OUT")
		)
		(pad "2" smd rect
			(at 0 0.9652 180)
			(size 1.397 1.143)
			(layers "F.Cu" "F.Mask" "F.Paste")
			(net "GND")
		)
	)
	(footprint ""
		(layer "F.Cu")
		(at 89.52992 -149.317456 180)
		(property "Reference" "R33"
			(at 0 0 180)
			(layer "F.SilkS")
			(hide yes)
			(effects
				(font
					(size 1.27 1.27)
				)
			)
		)
		(property "Value" "4K7R2F-GP"
			(at 0.064008 -3.993896 180)
			(unlocked yes)
			(layer "F.Fab")
			(hide yes)
			(effects
				(font
					(size 1.016 1.016)
					(thickness 0.1524)
				)
			)
		)
		(property "Device Type" "R402H16"
			(at 0.064008 -5.517896 180)
			(unlocked yes)
			(layer "F.Fab")
			(hide yes)
			(effects
				(font
					(size 1.016 1.016)
					(thickness 0.1524)
				)
			)
		)
		(duplicate_pad_numbers_are_jumpers no)
		(fp_line
			(start 0.508 -0.9398)
			(end -0.508 -0.9398)
			(stroke
				(width 0.1524)
				(type default)
			)
			(layer "F.SilkS")
		)
		(fp_line
			(start -0.508 -0.9398)
			(end -0.508 0.9398)
			(stroke
				(width 0.1524)
				(type default)
			)
			(layer "F.SilkS")
		)
		(fp_rect
			(start -0.508 0.9398)
			(end 0.508 -0.9398)
			(stroke
				(width 0)
				(type default)
			)
			(fill no)
			(layer "F.CrtYd")
		)
		(fp_rect
			(start -0.508 0.9398)
			(end 0.508 -0.9398)
			(stroke
				(width 0)
				(type default)
			)
			(fill no)
			(layer "F.Fab")
		)
		(pad "1" smd custom
			(at 0 -0.4445 180)
			(size 0.1397 0.1397)
			(layers "F.Cu" "F.Mask" "F.Paste")
			(net "P3V3_STBY")
			(options
				(clearance outline)
				(anchor circle)
			)
			(primitives
				(gr_poly
					(pts
						(arc
							(start -0.1778 -0.2794)
							(mid -0.249642 -0.249642)
							(end -0.2794 -0.1778)
						)
						(arc
							(start -0.2794 0.1778)
							(mid -0.249642 0.249642)
							(end -0.1778 0.2794)
						)
						(arc
							(start 0.1778 0.2794)
							(mid 0.249642 0.249642)
							(end 0.2794 0.1778)
						)
						(arc
							(start 0.2794 -0.1778)
							(mid 0.249642 -0.249642)
							(end 0.1778 -0.2794)
						)
					)
					(width 0)
					(fill yes)
				)
			)
		)
		(pad "2" smd custom
			(at 0 0.4445 180)
			(size 0.1397 0.1397)
			(layers "F.Cu" "F.Mask" "F.Paste")
			(net "USB_EN_1")
			(options
				(clearance outline)
				(anchor circle)
			)
			(primitives
				(gr_poly
					(pts
						(arc
							(start -0.1778 -0.2794)
							(mid -0.249642 -0.249642)
							(end -0.2794 -0.1778)
						)
						(arc
							(start -0.2794 0.1778)
							(mid -0.249642 0.249642)
							(end -0.1778 0.2794)
						)
						(arc
							(start 0.1778 0.2794)
							(mid 0.249642 0.249642)
							(end 0.2794 0.1778)
						)
						(arc
							(start 0.2794 -0.1778)
							(mid 0.249642 -0.249642)
							(end 0.1778 -0.2794)
						)
					)
					(width 0)
					(fill yes)
				)
			)
		)
	)
	(footprint ""
		(layer "F.Cu")
		(at 171.2468 -127.9906 90)
		(property "Reference" "R527"
			(at 0 0 90)
			(layer "F.SilkS")
			(hide yes)
			(effects
				(font
					(size 1.27 1.27)
				)
			)
		)
		(property "Value" "4K7R2F-GP"
			(at 0.064008 -3.993896 90)
			(unlocked yes)
			(layer "F.Fab")
			(hide yes)
			(effects
				(font
					(size 1.016 1.016)
					(thickness 0.1524)
				)
			)
		)
		(property "Device Type" "R402H16"
			(at 0.064008 -5.517896 90)
			(unlocked yes)
			(layer "F.Fab")
			(hide yes)
			(effects
				(font
					(size 1.016 1.016)
					(thickness 0.1524)
				)
			)
		)
		(duplicate_pad_numbers_are_jumpers no)
		(fp_line
			(start 0.508 -0.9398)
			(end -0.508 -0.9398)
			(stroke
				(width 0.1524)
				(type default)
			)
			(layer "F.SilkS")
		)
		(fp_line
			(start -0.508 -0.9398)
			(end -0.508 0.9398)
			(stroke
				(width 0.1524)
				(type default)
			)
			(layer "F.SilkS")
		)
		(fp_rect
			(start -0.508 0.9398)
			(end 0.508 -0.9398)
			(stroke
				(width 0)
				(type default)
			)
			(fill no)
			(layer "F.CrtYd")
		)
		(fp_rect
			(start -0.508 0.9398)
			(end 0.508 -0.9398)
			(stroke
				(width 0)
				(type default)
			)
			(fill no)
			(layer "F.Fab")
		)
		(pad "1" smd custom
			(at 0 -0.4445 90)
			(size 0.1397 0.1397)
			(layers "F.Cu" "F.Mask" "F.Paste")
			(net "P3V3")
			(options
				(clearance outline)
				(anchor circle)
			)
			(primitives
				(gr_poly
					(pts
						(arc
							(start -0.1778 -0.2794)
							(mid -0.249642 -0.249642)
							(end -0.2794 -0.1778)
						)
						(arc
							(start -0.2794 0.1778)
							(mid -0.249642 0.249642)
							(end -0.1778 0.2794)
						)
						(arc
							(start 0.1778 0.2794)
							(mid 0.249642 0.249642)
							(end 0.2794 0.1778)
						)
						(arc
							(start 0.2794 -0.1778)
							(mid 0.249642 -0.249642)
							(end 0.1778 -0.2794)
						)
					)
					(width 0)
					(fill yes)
				)
			)
		)
		(pad "2" smd custom
			(at 0 0.4445 90)
			(size 0.1397 0.1397)
			(layers "F.Cu" "F.Mask" "F.Paste")
			(net "Q7_G")
			(options
				(clearance outline)
				(anchor circle)
			)
			(primitives
				(gr_poly
					(pts
						(arc
							(start -0.1778 -0.2794)
							(mid -0.249642 -0.249642)
							(end -0.2794 -0.1778)
						)
						(arc
							(start -0.2794 0.1778)
							(mid -0.249642 0.249642)
							(end -0.1778 0.2794)
						)
						(arc
							(start 0.1778 0.2794)
							(mid 0.249642 0.249642)
							(end 0.2794 0.1778)
						)
						(arc
							(start 0.2794 -0.1778)
							(mid 0.249642 -0.249642)
							(end 0.1778 -0.2794)
						)
					)
					(width 0)
					(fill yes)
				)
			)
		)
	)
)
